(kicad_pcb
	(version 20241229)
	(generator "pcbnew")
	(generator_version "9.0")
	(general
		(thickness 1.294)
		(legacy_teardrops no)
	)
	(paper "A3")
	(title_block
		(title "Kintex 410T devboard")
		(date "2024-04-03")
		(rev "1.1.2")
		(comment 9 "footprints 423-427 of 975")
	)
	(layers
		(0 "F.Cu" mixed)
		(4 "In1.Cu" power)
		(6 "In2.Cu" power)
		(8 "In3.Cu" mixed)
		(10 "In4.Cu" power)
		(12 "In5.Cu" mixed)
		(14 "In6.Cu" power)
		(16 "In7.Cu" mixed)
		(18 "In8.Cu" power)
		(2 "B.Cu" mixed)
		(9 "F.Adhes" user "F.Adhesive")
		(11 "B.Adhes" user "B.Adhesive")
		(13 "F.Paste" user)
		(15 "B.Paste" user)
		(5 "F.SilkS" user "F.Silkscreen")
		(7 "B.SilkS" user "B.Silkscreen")
		(1 "F.Mask" user)
		(3 "B.Mask" user)
		(17 "Dwgs.User" user "User.Drawings")
		(19 "Cmts.User" user "User.Comments")
		(21 "Eco1.User" user "User.Eco1")
		(23 "Eco2.User" user "User.Eco2")
		(25 "Edge.Cuts" user)
		(27 "Margin" user)
		(31 "F.CrtYd" user "F.Courtyard")
		(29 "B.CrtYd" user "B.Courtyard")
		(35 "F.Fab" user)
		(33 "B.Fab" user)
	)
	(footprint "antmicro-footprints:Nexperia_SOD128"
		(layer "F.Cu")
		(at 188.675 172.349)
		(property "Reference" "D16"
			(at -3.225 -0.049 90)
			(layer "F.SilkS")
			(effects
				(font
					(size 0.7 0.7)
					(thickness 0.15)
				)
			)
		)
		(property "Value" "PMEG3050EP,115"
			(at 0 2.4765 0)
			(layer "F.Fab")
			(effects
				(font
					(size 1 1)
					(thickness 0.15)
				)
			)
		)
		(property "Description" "Schottky Rectifier, 30 V, 5 A, Single, SOD-128, 2 Pins, 360 mV"
			(at 0 0 0)
			(layer "F.Fab")
			(hide yes)
			(effects
				(font
					(size 1.27 1.27)
					(thickness 0.15)
				)
			)
		)
		(property "Author" "Antmicro"
			(at 0 0 0)
			(layer "F.Fab")
			(hide yes)
			(effects
				(font
					(size 1 1)
					(thickness 0.15)
				)
			)
		)
		(property "DNP" "DNP"
			(at 0 0 0)
			(layer "F.Fab")
			(hide yes)
			(effects
				(font
					(size 1 1)
					(thickness 0.15)
				)
			)
		)
		(property "License" "Apache-2.0"
			(at 0 0 0)
			(layer "F.Fab")
			(hide yes)
			(effects
				(font
					(size 1 1)
					(thickness 0.15)
				)
			)
		)
		(property "MPN" "PMEG3050EP,115"
			(at 0 0 0)
			(layer "F.Fab")
			(hide yes)
			(effects
				(font
					(size 1 1)
					(thickness 0.15)
				)
			)
		)
		(property "Manufacturer" "Nexperia"
			(at 0 0 0)
			(layer "F.Fab")
			(hide yes)
			(effects
				(font
					(size 1 1)
					(thickness 0.15)
				)
			)
		)
		(property "dnp" ""
			(at 0 0 0)
			(layer "F.Fab")
			(hide yes)
			(effects
				(font
					(size 1 1)
					(thickness 0.15)
				)
			)
		)
		(property "exclude_from_bom" ""
			(at 0 0 0)
			(layer "F.Fab")
			(hide yes)
			(effects
				(font
					(size 1 1)
					(thickness 0.15)
				)
			)
		)
		(sheetname "Power supply")
		(sheetfile "power-supply.kicad_sch")
		(attr smd exclude_from_bom)
		(fp_line
			(start -2.121 -1.474)
			(end -2.121 -1.287)
			(stroke
				(width 0.15)
				(type solid)
			)
			(layer "F.SilkS")
		)
		(fp_line
			(start -2.121 1.284)
			(end -2.121 1.473)
			(stroke
				(width 0.15)
				(type solid)
			)
			(layer "F.SilkS")
		)
		(fp_line
			(start -2.121 1.473)
			(end 2.12 1.473)
			(stroke
				(width 0.15)
				(type solid)
			)
			(layer "F.SilkS")
		)
		(fp_line
			(start -1.6 -1.4)
			(end -1.6 1.4)
			(stroke
				(width 0.12)
				(type solid)
			)
			(layer "F.SilkS")
		)
		(fp_line
			(start 2.12 -1.474)
			(end -2.121 -1.474)
			(stroke
				(width 0.15)
				(type solid)
			)
			(layer "F.SilkS")
		)
		(fp_line
			(start 2.12 -1.287)
			(end 2.12 -1.474)
			(stroke
				(width 0.15)
				(type solid)
			)
			(layer "F.SilkS")
		)
		(fp_line
			(start 2.12 1.473)
			(end 2.12 1.284)
			(stroke
				(width 0.15)
				(type solid)
			)
			(layer "F.SilkS")
		)
		(fp_rect
			(start -2.8 -1.6)
			(end 2.8 1.6)
			(stroke
				(width 0.05)
				(type solid)
			)
			(fill no)
			(layer "F.CrtYd")
		)
		(fp_line
			(start -2.503 -0.954)
			(end -2.503 0.952)
			(stroke
				(width 0.15)
				(type solid)
			)
			(layer "F.Fab")
		)
		(fp_line
			(start -2.503 0.952)
			(end -1.994 0.952)
			(stroke
				(width 0.15)
				(type solid)
			)
			(layer "F.Fab")
		)
		(fp_line
			(start -1.994 -1.347)
			(end -1.994 1.346)
			(stroke
				(width 0.15)
				(type solid)
			)
			(layer "F.Fab")
		)
		(fp_line
			(start -1.994 -0.954)
			(end -2.503 -0.954)
			(stroke
				(width 0.15)
				(type solid)
			)
			(layer "F.Fab")
		)
		(fp_line
			(start -1.994 -0.675)
			(end -1.321 -1.347)
			(stroke
				(width 0.15)
				(type solid)
			)
			(layer "F.Fab")
		)
		(fp_line
			(start -1.994 0.673)
			(end -1.321 1.346)
			(stroke
				(width 0.15)
				(type solid)
			)
			(layer "F.Fab")
		)
		(fp_line
			(start -1.994 0.952)
			(end -1.994 -0.954)
			(stroke
				(width 0.15)
				(type solid)
			)
			(layer "F.Fab")
		)
		(fp_line
			(start -1.994 1.346)
			(end 1.993 1.346)
			(stroke
				(width 0.15)
				(type solid)
			)
			(layer "F.Fab")
		)
		(fp_line
			(start 1.993 -1.347)
			(end -1.994 -1.347)
			(stroke
				(width 0.15)
				(type solid)
			)
			(layer "F.Fab")
		)
		(fp_line
			(start 1.993 -0.954)
			(end 1.993 0.952)
			(stroke
				(width 0.15)
				(type solid)
			)
			(layer "F.Fab")
		)
		(fp_line
			(start 1.993 0.952)
			(end 2.5 0.952)
			(stroke
				(width 0.15)
				(type solid)
			)
			(layer "F.Fab")
		)
		(fp_line
			(start 1.993 1.346)
			(end 1.993 -1.347)
			(stroke
				(width 0.15)
				(type solid)
			)
			(layer "F.Fab")
		)
		(fp_line
			(start 2.5 -0.954)
			(end 1.993 -0.954)
			(stroke
				(width 0.15)
				(type solid)
			)
			(layer "F.Fab")
		)
		(fp_line
			(start 2.5 0.952)
			(end 2.5 -0.954)
			(stroke
				(width 0.15)
				(type solid)
			)
			(layer "F.Fab")
		)
		(pad "1" smd rect
			(at -2.298 0)
			(size 0.8096 1.905)
			(layers "F.Cu" "F.Mask" "F.Paste")
			(net 702 "VDC")
			(pinfunction "1")
			(pintype "passive")
		)
		(pad "2" smd rect
			(at 2.297 0)
			(size 0.8096 1.905)
			(layers "F.Cu" "F.Mask" "F.Paste")
			(net 700 "/Power supply/USB_PD_VBUS")
			(pinfunction "2")
			(pintype "passive")
		)
	)
	(footprint "antmicro-footprints:R_0402_1005Metric"
		(layer "F.Cu")
		(at 170.7 152)
		(descr "Resistor SMD 0402")
		(tags "resistor SMD 0402")
		(property "Reference" "R35"
			(at -0.95 1.4 0)
			(layer "F.SilkS")
			(effects
				(font
					(size 0.7 0.7)
					(thickness 0.15)
				)
				(justify left bottom)
			)
		)
		(property "Value" "R_240R_0402"
			(at 0 1.4 0)
			(layer "F.Fab")
			(effects
				(font
					(size 0.7 0.7)
					(thickness 0.15)
				)
				(justify left bottom)
			)
		)
		(property "Description" "SMD Chip Resistor, 240 ohm, ± 1%, 63 mW, 0402 [1005 Metric], Thick Film, General Purpose"
			(at 0 0 0)
			(layer "F.Fab")
			(hide yes)
			(effects
				(font
					(size 1.27 1.27)
					(thickness 0.15)
				)
			)
		)
		(property "Author" "Antmicro"
			(at 0 0 0)
			(layer "F.Fab")
			(hide yes)
			(effects
				(font
					(size 1 1)
					(thickness 0.15)
				)
			)
		)
		(property "License" "Apache-2.0"
			(at 0 0 0)
			(layer "F.Fab")
			(hide yes)
			(effects
				(font
					(size 1 1)
					(thickness 0.15)
				)
			)
		)
		(property "MPN" "CR0402-FX-2400GLF"
			(at 0 0 0)
			(layer "F.Fab")
			(hide yes)
			(effects
				(font
					(size 1 1)
					(thickness 0.15)
				)
			)
		)
		(property "Manufacturer" "Bourns"
			(at 0 0 0)
			(layer "F.Fab")
			(hide yes)
			(effects
				(font
					(size 1 1)
					(thickness 0.15)
				)
			)
		)
		(property "Tolerance" "1%"
			(at 0 0 0)
			(layer "F.Fab")
			(hide yes)
			(effects
				(font
					(size 1 1)
					(thickness 0.15)
				)
			)
		)
		(property "Val" "240R"
			(at 0 0 0)
			(layer "F.Fab")
			(hide yes)
			(effects
				(font
					(size 1 1)
					(thickness 0.15)
				)
			)
		)
		(sheetname "DRAM + SRAM")
		(sheetfile "ram.kicad_sch")
		(attr smd)
		(fp_rect
			(start -0.925 -0.47)
			(end 0.925 0.47)
			(stroke
				(width 0.05)
				(type default)
			)
			(fill no)
			(layer "F.CrtYd")
		)
		(fp_rect
			(start -0.5 -0.25)
			(end 0.5 0.25)
			(stroke
				(width 0.15)
				(type solid)
			)
			(fill no)
			(layer "F.Fab")
		)
		(pad "1" smd roundrect
			(at -0.48 0)
			(size 0.59 0.64)
			(layers "F.Cu" "F.Mask" "F.Paste")
			(roundrect_rratio 0.25)
			(net 1 "GND")
			(pintype "passive")
		)
		(pad "2" smd roundrect
			(at 0.48 0)
			(size 0.59 0.64)
			(layers "F.Cu" "F.Mask" "F.Paste")
			(roundrect_rratio 0.25)
			(net 555 "/DRAM + SRAM/DDR_ZQ")
			(pintype "passive")
		)
	)
	(footprint "antmicro-footprints:R_0402_1005Metric"
		(layer "F.Cu")
		(at 214.88 154.7 90)
		(descr "Resistor SMD 0402")
		(tags "resistor SMD 0402")
		(property "Reference" "R73"
			(at 0.95 -0.33 270)
			(layer "F.SilkS")
			(effects
				(font
					(size 0.7 0.7)
					(thickness 0.15)
				)
				(justify left bottom)
			)
		)
		(property "Value" "R_100R_0402"
			(at 0 1.4 90)
			(layer "F.Fab")
			(effects
				(font
					(size 0.7 0.7)
					(thickness 0.15)
				)
				(justify left bottom)
			)
		)
		(property "Description" "SMD Chip Resistor, 100 ohm, ± 1%, 62.5 mW, 0402 [1005 Metric], Thick Film, General Purpose"
			(at 0 0 90)
			(layer "F.Fab")
			(hide yes)
			(effects
				(font
					(size 1.27 1.27)
					(thickness 0.15)
				)
			)
		)
		(property "Author" "Antmicro"
			(at 369.58 -60.18 0)
			(layer "F.Fab")
			(hide yes)
			(effects
				(font
					(size 1 1)
					(thickness 0.15)
				)
			)
		)
		(property "DNP" "DNP"
			(at 369.58 -60.18 0)
			(layer "F.Fab")
			(hide yes)
			(effects
				(font
					(size 1 1)
					(thickness 0.15)
				)
			)
		)
		(property "License" "Apache-2.0"
			(at 369.58 -60.18 0)
			(layer "F.Fab")
			(hide yes)
			(effects
				(font
					(size 1 1)
					(thickness 0.15)
				)
			)
		)
		(property "MPN" "CR0402-FX-1000GLF"
			(at 369.58 -60.18 0)
			(layer "F.Fab")
			(hide yes)
			(effects
				(font
					(size 1 1)
					(thickness 0.15)
				)
			)
		)
		(property "Manufacturer" "Bourns"
			(at 369.58 -60.18 0)
			(layer "F.Fab")
			(hide yes)
			(effects
				(font
					(size 1 1)
					(thickness 0.15)
				)
			)
		)
		(property "Tolerance" "1%"
			(at 369.58 -60.18 0)
			(layer "F.Fab")
			(hide yes)
			(effects
				(font
					(size 1 1)
					(thickness 0.15)
				)
			)
		)
		(property "Val" "100R"
			(at 369.58 -60.18 0)
			(layer "F.Fab")
			(hide yes)
			(effects
				(font
					(size 1 1)
					(thickness 0.15)
				)
			)
		)
		(property "dnp" ""
			(at 369.58 -60.18 0)
			(layer "F.Fab")
			(hide yes)
			(effects
				(font
					(size 1 1)
					(thickness 0.15)
				)
			)
		)
		(property "exclude_from_bom" ""
			(at 369.58 -60.18 0)
			(layer "F.Fab")
			(hide yes)
			(effects
				(font
					(size 1 1)
					(thickness 0.15)
				)
			)
		)
		(sheetname "SPI Flash + SD Card")
		(sheetfile "spi-flash.kicad_sch")
		(attr smd exclude_from_bom)
		(fp_rect
			(start -0.925 -0.47)
			(end 0.925 0.47)
			(stroke
				(width 0.05)
				(type default)
			)
			(fill no)
			(layer "F.CrtYd")
		)
		(fp_rect
			(start -0.5 -0.25)
			(end 0.5 0.25)
			(stroke
				(width 0.15)
				(type solid)
			)
			(fill no)
			(layer "F.Fab")
		)
		(pad "1" smd roundrect
			(at -0.48 0 90)
			(size 0.59 0.64)
			(layers "F.Cu" "F.Mask" "F.Paste")
			(roundrect_rratio 0.25)
			(net 1 "GND")
			(pintype "passive")
		)
		(pad "2" smd roundrect
			(at 0.48 0 90)
			(size 0.59 0.64)
			(layers "F.Cu" "F.Mask" "F.Paste")
			(roundrect_rratio 0.25)
			(net 408 "/FPGA Bank 33 & 34/USR_FLASH_0.CLK")
			(pintype "passive")
		)
	)
	(footprint "antmicro-footprints:C_0402_1005Metric"
		(layer "F.Cu")
		(at 153.8 146.65 -90)
		(descr "Capacitor SMD 0402")
		(tags "capacitor SMD 0402")
		(property "Reference" "C343"
			(at -3.65 -0.4 90)
			(layer "F.SilkS")
			(effects
				(font
					(size 0.7 0.7)
					(thickness 0.15)
				)
				(justify right bottom)
			)
		)
		(property "Value" "C_100n_0402"
			(at 0 1.4 90)
			(layer "F.Fab")
			(effects
				(font
					(size 0.7 0.7)
					(thickness 0.15)
				)
				(justify right bottom)
			)
		)
		(property "Description" "SMD Multilayer Ceramic Capacitor, 0.1 µF, 50 V, 0402 [1005 Metric], ± 10%, X5R, GRM Series"
			(at 0 0 270)
			(layer "F.Fab")
			(hide yes)
			(effects
				(font
					(size 1.27 1.27)
					(thickness 0.15)
				)
			)
		)
		(property "Author" "Antmicro"
			(at 7.15 300.45 0)
			(layer "F.Fab")
			(hide yes)
			(effects
				(font
					(size 1 1)
					(thickness 0.15)
				)
			)
		)
		(property "Dielectric" "X5R"
			(at 7.15 300.45 0)
			(layer "F.Fab")
			(hide yes)
			(effects
				(font
					(size 1 1)
					(thickness 0.15)
				)
			)
		)
		(property "License" "Apache-2.0"
			(at 7.15 300.45 0)
			(layer "F.Fab")
			(hide yes)
			(effects
				(font
					(size 1 1)
					(thickness 0.15)
				)
			)
		)
		(property "MPN" "GRM155R61H104KE14D"
			(at 7.15 300.45 0)
			(layer "F.Fab")
			(hide yes)
			(effects
				(font
					(size 1 1)
					(thickness 0.15)
				)
			)
		)
		(property "Manufacturer" "Murata"
			(at 7.15 300.45 0)
			(layer "F.Fab")
			(hide yes)
			(effects
				(font
					(size 1 1)
					(thickness 0.15)
				)
			)
		)
		(property "Val" "100n"
			(at 7.15 300.45 0)
			(layer "F.Fab")
			(hide yes)
			(effects
				(font
					(size 1 1)
					(thickness 0.15)
				)
			)
		)
		(property "Voltage" "50V"
			(at 7.15 300.45 0)
			(layer "F.Fab")
			(hide yes)
			(effects
				(font
					(size 1 1)
					(thickness 0.15)
				)
			)
		)
		(sheetname "DC-DC Converters")
		(sheetfile "dc-dc.kicad_sch")
		(attr smd)
		(fp_rect
			(start -0.925 -0.47)
			(end 0.925 0.47)
			(stroke
				(width 0.05)
				(type default)
			)
			(fill no)
			(layer "F.CrtYd")
		)
		(fp_line
			(start -0.494 0.248)
			(end -0.494 -0.25)
			(stroke
				(width 0.15)
				(type solid)
			)
			(layer "F.Fab")
		)
		(fp_line
			(start 0.504 0.248)
			(end -0.494 0.248)
			(stroke
				(width 0.15)
				(type solid)
			)
			(layer "F.Fab")
		)
		(fp_line
			(start -0.494 -0.25)
			(end 0.504 -0.25)
			(stroke
				(width 0.15)
				(type solid)
			)
			(layer "F.Fab")
		)
		(fp_line
			(start 0.504 -0.25)
			(end 0.504 0.248)
			(stroke
				(width 0.15)
				(type solid)
			)
			(layer "F.Fab")
		)
		(pad "1" smd roundrect
			(at -0.48 0 270)
			(size 0.59 0.64)
			(layers "F.Cu" "F.Mask" "F.Paste")
			(roundrect_rratio 0.25)
			(net 1 "GND")
			(pintype "passive")
		)
		(pad "2" smd roundrect
			(at 0.48 0 270)
			(size 0.59 0.64)
			(layers "F.Cu" "F.Mask" "F.Paste")
			(roundrect_rratio 0.25)
			(net 24 "+3V3")
			(pintype "passive")
		)
	)
	(footprint "antmicro-footprints:QFN-2L_1.6x1x0.55mm"
		(layer "F.Cu")
		(at 225.05 159.8)
		(property "Reference" "D14"
			(at -1.2 1.4 0)
			(layer "F.SilkS")
			(effects
				(font
					(size 0.7 0.7)
					(thickness 0.15)
				)
				(justify left bottom)
			)
		)
		(property "Value" "ESDA25P35-1U1M"
			(at 0 1.7 0)
			(layer "F.Fab")
			(effects
				(font
					(size 0.7 0.7)
					(thickness 0.15)
				)
				(justify left bottom)
			)
		)
		(property "Description" "Unidirectional TVS, 30 kV, QFN-2L, 22 V, 195 pF"
			(at 0 0 0)
			(layer "F.Fab")
			(hide yes)
			(effects
				(font
					(size 1.27 1.27)
					(thickness 0.15)
				)
			)
		)
		(property "Author" "Antmicro"
			(at 0 0 0)
			(layer "F.Fab")
			(hide yes)
			(effects
				(font
					(size 1 1)
					(thickness 0.15)
				)
			)
		)
		(property "License" "Apache-2.0"
			(at 0 0 0)
			(layer "F.Fab")
			(hide yes)
			(effects
				(font
					(size 1 1)
					(thickness 0.15)
				)
			)
		)
		(property "MPN" "ESDA25P35-1U1M"
			(at 0 0 0)
			(layer "F.Fab")
			(hide yes)
			(effects
				(font
					(size 1 1)
					(thickness 0.15)
				)
			)
		)
		(property "Manufacturer" "STMicroelectronics"
			(at 0 0 0)
			(layer "F.Fab")
			(hide yes)
			(effects
				(font
					(size 1 1)
					(thickness 0.15)
				)
			)
		)
		(property "Public" "False"
			(at 0 0 0)
			(layer "F.Fab")
			(hide yes)
			(effects
				(font
					(size 1 1)
					(thickness 0.15)
				)
			)
		)
		(sheetname "Power supply")
		(sheetfile "power-supply.kicad_sch")
		(attr smd)
		(fp_line
			(start -1.2 -0.4)
			(end -1.2 0.4)
			(stroke
				(width 0.15)
				(type solid)
			)
			(layer "F.SilkS")
		)
		(fp_line
			(start 0.27 -0.3)
			(end -0.27 -0.3)
			(stroke
				(width 0.15)
				(type solid)
			)
			(layer "F.SilkS")
		)
		(fp_line
			(start 0.27 0.3)
			(end -0.27 0.3)
			(stroke
				(width 0.15)
				(type solid)
			)
			(layer "F.SilkS")
		)
		(fp_rect
			(start 1.25 0.65)
			(end -1.25 -0.65)
			(stroke
				(width 0.05)
				(type solid)
			)
			(fill no)
			(layer "F.CrtYd")
		)
		(fp_line
			(start -0.199 -0.202)
			(end -0.199 0.1)
			(stroke
				(width 0.15)
				(type solid)
			)
			(layer "F.Fab")
		)
		(fp_line
			(start -0.199 0)
			(end -0.597 0)
			(stroke
				(width 0.15)
				(type solid)
			)
			(layer "F.Fab")
		)
		(fp_line
			(start -0.199 0.2)
			(end -0.199 0.1)
			(stroke
				(width 0.15)
				(type solid)
			)
			(layer "F.Fab")
		)
		(fp_line
			(start -0.101 0)
			(end 0.201 0.2)
			(stroke
				(width 0.15)
				(type solid)
			)
			(layer "F.Fab")
		)
		(fp_line
			(start 0.201 -0.202)
			(end -0.101 0)
			(stroke
				(width 0.15)
				(type solid)
			)
			(layer "F.Fab")
		)
		(fp_line
			(start 0.201 0)
			(end 0.201 -0.202)
			(stroke
				(width 0.15)
				(type solid)
			)
			(layer "F.Fab")
		)
		(fp_line
			(start 0.201 0.2)
			(end 0.201 0)
			(stroke
				(width 0.15)
				(type solid)
			)
			(layer "F.Fab")
		)
		(fp_line
			(start 0.599 0)
			(end 0.201 0)
			(stroke
				(width 0.15)
				(type solid)
			)
			(layer "F.Fab")
		)
		(fp_rect
			(start 0.848 0.4)
			(end -0.85 -0.402)
			(stroke
				(width 0.15)
				(type solid)
			)
			(fill no)
			(layer "F.Fab")
		)
		(pad "1" smd roundrect
			(at -0.7 0 180)
			(size 0.8 1)
			(layers "F.Cu" "F.Mask" "F.Paste")
			(roundrect_rratio 0.2)
			(net 700 "/Power supply/USB_PD_VBUS")
			(pinfunction "C")
			(pintype "passive")
		)
		(pad "2" smd roundrect
			(at 0.7 0 180)
			(size 0.8 1)
			(layers "F.Cu" "F.Mask" "F.Paste")
			(roundrect_rratio 0.2)
			(net 1 "GND")
			(pinfunction "A")
			(pintype "passive")
		)
	)
)
